# TIMECARD (Time Appliance Project (Time Card)) — schematic netlist excerpt (pin names and nets, part order shuffled) for the footprints in the layout excerpt that follows; sources: Cadence DE-HDL packaged netlist, KiCad conversion of R4006-B0001-02_R01.brd

R435  RESISTOR  100KOHM 1%  pkg SMC_0402R_H016  page 11 : \1\ = FPGA_FLASH_DQ1_MISO ; \2\ = XP3R3V_FPGA
C190  CAPACITOR  0.01UF 25V 10%  pkg SMC_0201R  page 30 : \1\ = XP1R2V_SS ; \2\ = SG

(kicad_pcb
	(version 20260206)
	(generator "pcbnew")
	(generator_version "10.0")
	(general
		(thickness 1.6)
		(legacy_teardrops no)
	)
	(paper "A4")
	(title_block
		(title "timecard-production-celestica-r4006 — R4006-B0001-02_R01.brd")
		(comment 1 "Time Appliance Project (Time Card) / footprints 200-201 of 1113")
	)
	(layers
		(0 "F.Cu" signal "TOP")
		(4 "In1.Cu" signal "L02_GND1")
		(6 "In2.Cu" signal "L03_SIG1")
		(8 "In3.Cu" signal "L04_GND2")
		(10 "In4.Cu" signal "L05_VCC1")
		(12 "In5.Cu" signal "L06_VCC2")
		(14 "In6.Cu" signal "L07_GND3")
		(16 "In7.Cu" signal "L08_SIG2")
		(18 "In8.Cu" signal "L09_GND4")
		(2 "B.Cu" signal "BOTTOM")
		(9 "F.Adhes" user "F.Adhesive")
		(11 "B.Adhes" user "B.Adhesive")
		(13 "F.Paste" user "Package Geometry/Pastemask Top")
		(15 "B.Paste" user "Package Geometry/Pastemask Bottom")
		(5 "F.SilkS" user "Ref Des/Silkscreen Top")
		(7 "B.SilkS" user "Ref Des/Silkscreen Bottom")
		(1 "F.Mask" user "Board Geometry/Soldermask Top")
		(3 "B.Mask" user "Board Geometry/Soldermask Bottom")
		(17 "Dwgs.User" user "User.Drawings")
		(19 "Cmts.User" user "User.Comments")
		(21 "Eco1.User" user "User.Eco1")
		(23 "Eco2.User" user "User.Eco2")
		(25 "Edge.Cuts" user "Board Geometry/Outline")
		(27 "Margin" user)
		(31 "F.CrtYd" user "Package Geometry/Place Bound Top")
		(29 "B.CrtYd" user "Package Geometry/Place Bound Bottom")
		(35 "F.Fab" user "Ref Des/Assembly Top")
		(33 "B.Fab" user "Ref Des/Assembly Bottom")
	)
	(footprint ""
		(layer "F.Cu")
		(at 116.205 -61.976 90)
		(property "Reference" "R435"
			(at 3.302 0.92837 90)
			(unlocked yes)
			(layer "F.SilkS")
			(effects
				(font
					(size 0.7874 0.5842)
					(thickness 0.1524)
				)
			)
		)
		(property "Value" "VAL*"
			(at 0.02032 2.13233 90)
			(unlocked yes)
			(layer "F.Fab")
			(hide yes)
			(effects
				(font
					(size 0.7874 0.5842)
					(thickness 0.1524)
				)
			)
		)
		(property "Tolerance" "TOL*"
			(at 0.044704 3.05435 90)
			(unlocked yes)
			(layer "Cmts.User")
			(hide yes)
			(effects
				(font
					(size 0.7874 0.5842)
					(thickness 0.1524)
				)
			)
		)
		(property "User Part Number" "PARTNUM*"
			(at 0.02032 4.024884 90)
			(unlocked yes)
			(layer "Cmts.User")
			(hide yes)
			(effects
				(font
					(size 0.7874 0.5842)
					(thickness 0.1524)
				)
			)
		)
		(property "Device Type" "RESISTOR-G155-11003-01,100KOHMA"
			(at 0.008382 1.210564 90)
			(unlocked yes)
			(layer "F.Fab")
			(hide yes)
			(effects
				(font
					(size 0.7874 0.5842)
					(thickness 0.1524)
				)
			)
		)
		(duplicate_pad_numbers_are_jumpers no)
		(fp_line
			(start 1.143 -0.5588)
			(end -1.143 -0.5588)
			(stroke
				(width 0.1)
				(type default)
			)
			(layer "F.SilkS")
		)
		(fp_line
			(start -1.143 -0.5588)
			(end -1.143 0.5588)
			(stroke
				(width 0.1)
				(type default)
			)
			(layer "F.SilkS")
		)
		(fp_line
			(start 1.143 0.5588)
			(end 1.143 -0.5588)
			(stroke
				(width 0.1)
				(type default)
			)
			(layer "F.SilkS")
		)
		(fp_line
			(start -1.143 0.5588)
			(end 1.143 0.5588)
			(stroke
				(width 0.1)
				(type default)
			)
			(layer "F.SilkS")
		)
		(fp_poly
			(pts
				(xy -1.143 0.5588) (xy 1.143 0.5588) (xy 1.143 -0.5588) (xy -1.143 -0.5588)
			)
			(stroke
				(width 0)
				(type default)
			)
			(fill no)
			(layer "F.CrtYd")
		)
		(fp_line
			(start 0.508 -0.3048)
			(end -0.508 -0.3048)
			(stroke
				(width 0.1)
				(type default)
			)
			(layer "F.Fab")
		)
		(fp_line
			(start -0.508 -0.3048)
			(end -0.508 0.3048)
			(stroke
				(width 0.1)
				(type default)
			)
			(layer "F.Fab")
		)
		(fp_line
			(start 0.508 0.3048)
			(end 0.508 -0.3048)
			(stroke
				(width 0.1)
				(type default)
			)
			(layer "F.Fab")
		)
		(fp_line
			(start -0.508 0.3048)
			(end 0.508 0.3048)
			(stroke
				(width 0.1)
				(type default)
			)
			(layer "F.Fab")
		)
		(pad "1" smd rect
			(at -0.5334 0 90)
			(size 0.7112 0.6096)
			(layers "F.Cu" "F.Mask" "F.Paste")
			(net "FPGA_FLASH_DQ1_MISO")
		)
		(pad "2" smd rect
			(at 0.5334 0 90)
			(size 0.7112 0.6096)
			(layers "F.Cu" "F.Mask" "F.Paste")
			(net "XP3R3V_FPGA")
		)
		(zone
			(layer "F.Cu")
			(hatch none 0.5)
			(connect_pads
				(clearance 0)
			)
			(min_thickness 0.25)
			(keepout
				(tracks not_allowed)
				(vias allowed)
				(pads allowed)
				(copperpour not_allowed)
				(footprints allowed)
			)
			(placement
				(enabled no)
				(sheetname "")
			)
			(fill
				(thermal_gap 0.5)
				(thermal_bridge_width 0.5)
				(island_removal_mode 0)
			)
			(polygon
				(pts
					(xy 116.5098 -61.8998) (xy 116.5098 -62.0522) (xy 115.9002 -62.0522) (xy 115.9002 -61.8998)
				)
			)
		)
		(zone
			(layer "F.Cu")
			(hatch none 0.5)
			(connect_pads
				(clearance 0)
			)
			(min_thickness 0.25)
			(keepout
				(tracks allowed)
				(vias not_allowed)
				(pads allowed)
				(copperpour not_allowed)
				(footprints allowed)
			)
			(placement
				(enabled no)
				(sheetname "")
			)
			(fill
				(thermal_gap 0.5)
				(thermal_bridge_width 0.5)
				(island_removal_mode 0)
			)
			(polygon
				(pts
					(xy 116.5098 -61.8998) (xy 116.5098 -62.0522) (xy 115.9002 -62.0522) (xy 115.9002 -61.8998)
				)
			)
		)
	)
	(footprint ""
		(layer "F.Cu")
		(at 101.1428 -78.486 90)
		(property "Reference" "C190"
			(at 1.524 2.02057 90)
			(unlocked yes)
			(layer "F.SilkS")
			(effects
				(font
					(size 0.7874 0.5842)
					(thickness 0.1524)
				)
			)
		)
		(property "Value" "VAL*"
			(at 0.193548 2.13614 90)
			(unlocked yes)
			(layer "F.Fab")
			(hide yes)
			(effects
				(font
					(size 0.7874 0.5842)
					(thickness 0.1524)
				)
			)
		)
		(property "Tolerance" "TOL*"
			(at 0.216154 3.1496 90)
			(unlocked yes)
			(layer "Cmts.User")
			(hide yes)
			(effects
				(font
					(size 0.7874 0.5842)
					(thickness 0.1524)
				)
			)
		)
		(property "Device Type" "CAPACITOR-G104-0B103-EK,0.01UFA"
			(at 0.184404 1.180592 90)
			(unlocked yes)
			(layer "F.Fab")
			(hide yes)
			(effects
				(font
					(size 0.7874 0.5842)
					(thickness 0.1524)
				)
			)
		)
		(property "User Part Number" "PARTNUM*"
			(at 0.216154 4.185666 90)
			(unlocked yes)
			(layer "Cmts.User")
			(hide yes)
			(effects
				(font
					(size 0.7874 0.5842)
					(thickness 0.1524)
				)
			)
		)
		(duplicate_pad_numbers_are_jumpers no)
		(fp_line
			(start 0.671322 -0.4445)
			(end 0.671322 0.4445)
			(stroke
				(width 0.1)
				(type default)
			)
			(layer "F.SilkS")
		)
		(fp_line
			(start -0.671322 -0.4445)
			(end 0.671322 -0.4445)
			(stroke
				(width 0.1)
				(type default)
			)
			(layer "F.SilkS")
		)
		(fp_line
			(start 0.671322 0.4445)
			(end -0.671322 0.4445)
			(stroke
				(width 0.1)
				(type default)
			)
			(layer "F.SilkS")
		)
		(fp_line
			(start -0.671322 0.4445)
			(end -0.671322 -0.4445)
			(stroke
				(width 0.1)
				(type default)
			)
			(layer "F.SilkS")
		)
		(fp_rect
			(start 0.671322 -0.4445)
			(end -0.671322 0.4445)
			(stroke
				(width 0)
				(type default)
			)
			(fill no)
			(layer "F.CrtYd")
		)
		(fp_line
			(start 0.31496 -0.1651)
			(end -0.31496 -0.1651)
			(stroke
				(width 0.1)
				(type default)
			)
			(layer "F.Fab")
		)
		(fp_line
			(start -0.31496 -0.1651)
			(end -0.31496 0.1651)
			(stroke
				(width 0.1)
				(type default)
			)
			(layer "F.Fab")
		)
		(fp_line
			(start 0.31496 0.1651)
			(end 0.31496 -0.1651)
			(stroke
				(width 0.1)
				(type default)
			)
			(layer "F.Fab")
		)
		(fp_line
			(start -0.31496 0.1651)
			(end 0.31496 0.1651)
			(stroke
				(width 0.1)
				(type default)
			)
			(layer "F.Fab")
		)
		(pad "1" smd rect
			(at -0.264922 0 90)
			(size 0.3048 0.381)
			(layers "F.Cu" "F.Mask" "F.Paste")
			(net "XP1R2V_SS")
		)
		(pad "2" smd rect
			(at 0.264922 0 90)
			(size 0.3048 0.381)
			(layers "F.Cu" "F.Mask" "F.Paste")
			(net "SG")
		)
		(zone
			(layer "F.Cu")
			(hatch none 0.5)
			(connect_pads
				(clearance 0)
			)
			(min_thickness 0.25)
			(keepout
				(tracks allowed)
				(vias not_allowed)
				(pads allowed)
				(copperpour not_allowed)
				(footprints allowed)
			)
			(placement
				(enabled no)
				(sheetname "")
			)
			(fill
				(thermal_gap 0.5)
				(thermal_bridge_width 0.5)
				(island_removal_mode 0)
			)
			(polygon
				(pts
					(xy 100.9523 -78.598522) (xy 100.9523 -78.373478) (xy 101.3333 -78.373478) (xy 101.3333 -78.598522)
				)
			)
		)
	)
)
